(kicad_pcb
	(version 20221018)
	(generator pcbnew)
	(general
    (thickness 1.518)
  )
	(paper "A4")
	(title_block
    (title "Kria K26 Devboard")
    (date "2024-03-26")
    (rev "1.2.5")
    (comment 1 "www.antmicro.com")
    (comment 2 "Antmicro Ltd.")
		(comment 9 "footprints 195-200 of 660")
	)
	(layers
    (0 "F.Cu" mixed)
    (1 "In1.Cu" power)
    (2 "In2.Cu" mixed)
    (3 "In3.Cu" power)
    (4 "In4.Cu" mixed)
    (5 "In5.Cu" power)
    (6 "In6.Cu" mixed)
    (31 "B.Cu" power)
    (32 "B.Adhes" user "B.Adhesive")
    (33 "F.Adhes" user "F.Adhesive")
    (34 "B.Paste" user)
    (35 "F.Paste" user)
    (36 "B.SilkS" user "B.Silkscreen")
    (37 "F.SilkS" user "F.Silkscreen")
    (38 "B.Mask" user)
    (39 "F.Mask" user)
    (40 "Dwgs.User" user "User.Drawings")
    (41 "Cmts.User" user "User.Comments")
    (42 "Eco1.User" user "User.Eco1")
    (43 "Eco2.User" user "User.Eco2")
    (44 "Edge.Cuts" user)
    (45 "Margin" user)
    (46 "B.CrtYd" user "B.Courtyard")
    (47 "F.CrtYd" user "F.Courtyard")
    (48 "B.Fab" user)
    (49 "F.Fab" user)
  )
	(footprint "kria-k26-devboard-footprints:R_0402_1005Metric" (layer "F.Cu")
    (at 78.475 119.25 -90)
    (descr "Resistor SMD 0402")
    (tags "resistor SMD 0402")
    (property "Author" "Antmicro")
    (property "DNP" "DNP")
    (property "License" "Apache-2.0")
    (property "MPN" "CR0402-FX-1501GLF")
    (property "Manufacturer" "Bourns")
    (property "Sheetfile" "camera.kicad_sch")
    (property "Sheetname" "Camera interface")
    (property "Tolerance" "1%")
    (property "Val" "1k5")
    (property "dnp" "")
    (property "exclude_from_bom" "")
    (property "ki_description" "1k5 resistor in 0402 package with 1% tolerance")
    (attr exclude_from_pos_files exclude_from_bom)
    (fp_text reference "R25" (at -0.85 -0.355 -90) (layer "F.SilkS")
        (effects (font (size 0.7 0.7) (thickness 0.15)) (justify left bottom))
    )
    (fp_text value "R_1k5_0402" (at 0 1.4 -90) (layer "F.Fab") hide
        (effects (font (size 0.7 0.7) (thickness 0.15)) (justify left bottom))
    )
    (fp_text user "${REFERENCE}" (at -0.95 3.168 -90) (layer "F.Fab") hide
        (effects (font (size 0.7 0.7) (thickness 0.15)) (justify left bottom))
    )
    (fp_text user "Author: Antmicro" (at -0.95 4.169 -90) (layer "F.Fab") hide
        (effects (font (size 0.7 0.7) (thickness 0.15)) (justify left bottom))
    )
    (fp_text user "License: Apache-2.0" (at -0.95 5.169 -90) (layer "F.Fab") hide
        (effects (font (size 0.7 0.7) (thickness 0.15)) (justify left bottom))
    )
    (fp_rect (start -0.93 -0.47) (end 0.93 0.47)
      (stroke (width 0.05) (type solid)) (fill none) (layer "F.CrtYd"))
    (fp_rect (start -0.5 -0.25) (end 0.5 0.25)
      (stroke (width 0.15) (type solid)) (fill none) (layer "F.Fab"))
    (pad "1" smd roundrect (at -0.485 0 270) (size 0.59 0.64) (layers "F.Cu" "F.Paste" "F.Mask") (roundrect_rratio 0.25)
      (net 322 "PL_1V8") (pintype "passive"))
    (pad "2" smd roundrect (at 0.485 0 270) (size 0.59 0.64) (layers "F.Cu" "F.Paste" "F.Mask") (roundrect_rratio 0.25)
      (net 193 "/Camera interface/CCI1_I2C_SCL_3V3") (pintype "passive"))
  )
	(footprint "kria-k26-devboard-footprints:R_0402_1005Metric" (layer "F.Cu")
    (at 80.375 119.25 -90)
    (descr "Resistor SMD 0402")
    (tags "resistor SMD 0402")
    (property "Author" "Antmicro")
    (property "DNP" "DNP")
    (property "License" "Apache-2.0")
    (property "MPN" "CR0402-FX-1501GLF")
    (property "Manufacturer" "Bourns")
    (property "Sheetfile" "camera.kicad_sch")
    (property "Sheetname" "Camera interface")
    (property "Tolerance" "1%")
    (property "Val" "1k5")
    (property "dnp" "")
    (property "exclude_from_bom" "")
    (property "ki_description" "1k5 resistor in 0402 package with 1% tolerance")
    (attr exclude_from_pos_files exclude_from_bom)
    (fp_text reference "R26" (at -0.85 -0.355 -90) (layer "F.SilkS")
        (effects (font (size 0.7 0.7) (thickness 0.15)) (justify left bottom))
    )
    (fp_text value "R_1k5_0402" (at 0 1.4 -90) (layer "F.Fab") hide
        (effects (font (size 0.7 0.7) (thickness 0.15)) (justify left bottom))
    )
    (fp_text user "${REFERENCE}" (at -0.95 3.168 -90) (layer "F.Fab") hide
        (effects (font (size 0.7 0.7) (thickness 0.15)) (justify left bottom))
    )
    (fp_text user "Author: Antmicro" (at -0.95 4.169 -90) (layer "F.Fab") hide
        (effects (font (size 0.7 0.7) (thickness 0.15)) (justify left bottom))
    )
    (fp_text user "License: Apache-2.0" (at -0.95 5.169 -90) (layer "F.Fab") hide
        (effects (font (size 0.7 0.7) (thickness 0.15)) (justify left bottom))
    )
    (fp_rect (start -0.93 -0.47) (end 0.93 0.47)
      (stroke (width 0.05) (type solid)) (fill none) (layer "F.CrtYd"))
    (fp_rect (start -0.5 -0.25) (end 0.5 0.25)
      (stroke (width 0.15) (type solid)) (fill none) (layer "F.Fab"))
    (pad "1" smd roundrect (at -0.485 0 270) (size 0.59 0.64) (layers "F.Cu" "F.Paste" "F.Mask") (roundrect_rratio 0.25)
      (net 322 "PL_1V8") (pintype "passive"))
    (pad "2" smd roundrect (at 0.485 0 270) (size 0.59 0.64) (layers "F.Cu" "F.Paste" "F.Mask") (roundrect_rratio 0.25)
      (net 195 "/Camera interface/CCI0_I2C_SCL_3V3") (pintype "passive"))
  )
	(footprint "kria-k26-devboard-footprints:R_0402_1005Metric" (layer "F.Cu")
    (at 79.425 119.25 -90)
    (descr "Resistor SMD 0402")
    (tags "resistor SMD 0402")
    (property "Author" "Antmicro")
    (property "DNP" "DNP")
    (property "License" "Apache-2.0")
    (property "MPN" "CR0402-FX-1501GLF")
    (property "Manufacturer" "Bourns")
    (property "Sheetfile" "camera.kicad_sch")
    (property "Sheetname" "Camera interface")
    (property "Tolerance" "1%")
    (property "Val" "1k5")
    (property "dnp" "")
    (property "exclude_from_bom" "")
    (property "ki_description" "1k5 resistor in 0402 package with 1% tolerance")
    (attr exclude_from_pos_files exclude_from_bom)
    (fp_text reference "R27" (at -0.85 -0.355 -90) (layer "F.SilkS")
        (effects (font (size 0.7 0.7) (thickness 0.15)) (justify left bottom))
    )
    (fp_text value "R_1k5_0402" (at 0 1.4 -90) (layer "F.Fab") hide
        (effects (font (size 0.7 0.7) (thickness 0.15)) (justify left bottom))
    )
    (fp_text user "Author: Antmicro" (at -0.95 4.169 -90) (layer "F.Fab") hide
        (effects (font (size 0.7 0.7) (thickness 0.15)) (justify left bottom))
    )
    (fp_text user "${REFERENCE}" (at -0.95 3.168 -90) (layer "F.Fab") hide
        (effects (font (size 0.7 0.7) (thickness 0.15)) (justify left bottom))
    )
    (fp_text user "License: Apache-2.0" (at -0.95 5.169 -90) (layer "F.Fab") hide
        (effects (font (size 0.7 0.7) (thickness 0.15)) (justify left bottom))
    )
    (fp_rect (start -0.93 -0.47) (end 0.93 0.47)
      (stroke (width 0.05) (type solid)) (fill none) (layer "F.CrtYd"))
    (fp_rect (start -0.5 -0.25) (end 0.5 0.25)
      (stroke (width 0.15) (type solid)) (fill none) (layer "F.Fab"))
    (pad "1" smd roundrect (at -0.485 0 270) (size 0.59 0.64) (layers "F.Cu" "F.Paste" "F.Mask") (roundrect_rratio 0.25)
      (net 322 "PL_1V8") (pintype "passive"))
    (pad "2" smd roundrect (at 0.485 0 270) (size 0.59 0.64) (layers "F.Cu" "F.Paste" "F.Mask") (roundrect_rratio 0.25)
      (net 194 "/Camera interface/CCI1_I2C_SDA_3V3") (pintype "passive"))
  )
	(footprint "kria-k26-devboard-footprints:SOT-563" (layer "F.Cu")
    (at 113.22 74.26 90)
    (property "Author" "Antmicro")
    (property "License" "Apache-2.0")
    (property "MPN" "82400152")
    (property "Manufacturer" "Würth Elektronik")
    (property "Sheetfile" "usb.kicad_sch")
    (property "Sheetname" "USB")
    (property "ki_description" "TVS diode")
    (property "ki_keywords" "SMT, DIODE, IC, ESD, TVS")
    (attr smd)
    (fp_text reference "U26" (at -2.04 -1.21 180) (layer "F.SilkS")
        (effects (font (size 0.7 0.7) (thickness 0.15)) (justify left bottom))
    )
    (fp_text value "82400152" (at 0 2 90) (layer "F.Fab") hide
        (effects (font (size 0.7 0.7) (thickness 0.15)) (justify left bottom))
    )
    (fp_text user "Author: Antmicro" (at -1.299 6.124 90) (layer "F.Fab") hide
        (effects (font (size 0.7 0.7) (thickness 0.15)) (justify left bottom))
    )
    (fp_text user "License: Apache-2.0" (at -1.299 4.924 90) (layer "F.Fab") hide
        (effects (font (size 0.7 0.7) (thickness 0.15)) (justify left bottom))
    )
    (fp_text user "${REFERENCE}" (at -1.299 7.323 90) (layer "F.Fab") hide
        (effects (font (size 0.7 0.7) (thickness 0.15)) (justify left bottom))
    )
    (fp_line (start -0.778 0.776) (end -0.778 0.949)
      (stroke (width 0.15) (type solid)) (layer "F.SilkS"))
    (fp_line (start -0.778 0.949) (end -0.424 0.949)
      (stroke (width 0.15) (type solid)) (layer "F.SilkS"))
    (fp_line (start -0.499 -0.974) (end -0.724 -0.778)
      (stroke (width 0.15) (type solid)) (layer "F.SilkS"))
    (fp_line (start 0.776 -0.974) (end 0.526 -0.974)
      (stroke (width 0.15) (type solid)) (layer "F.SilkS"))
    (fp_line (start 0.776 -0.974) (end 0.776 -0.778)
      (stroke (width 0.15) (type solid)) (layer "F.SilkS"))
    (fp_line (start 0.776 0.776) (end 0.776 0.972)
      (stroke (width 0.15) (type solid)) (layer "F.SilkS"))
    (fp_line (start 0.776 0.972) (end 0.526 0.972)
      (stroke (width 0.15) (type solid)) (layer "F.SilkS"))
    (fp_circle (center -0.903 -0.999) (end -0.952 -0.95)
      (stroke (width 0.15) (type solid)) (fill solid) (layer "F.SilkS"))
    (fp_rect (start 1.19 -1.12) (end -1.2 1.1)
      (stroke (width 0.05) (type solid)) (fill none) (layer "F.CrtYd"))
    (fp_line (start -0.653 -0.678) (end -0.653 0.847)
      (stroke (width 0.15) (type solid)) (layer "F.Fab"))
    (fp_line (start -0.453 -0.849) (end -0.653 -0.678)
      (stroke (width 0.15) (type solid)) (layer "F.Fab"))
    (fp_line (start -0.453 -0.849) (end 0.651 -0.849)
      (stroke (width 0.15) (type solid)) (layer "F.Fab"))
    (fp_line (start 0.651 -0.849) (end 0.651 0.847)
      (stroke (width 0.15) (type solid)) (layer "F.Fab"))
    (fp_line (start 0.651 0.847) (end -0.653 0.847)
      (stroke (width 0.15) (type solid)) (layer "F.Fab"))
    (pad "1" smd roundrect (at -0.749 -0.499) (size 0.3 0.6) (layers "F.Cu" "F.Paste" "F.Mask") (roundrect_rratio 0.25)
      (net 78 "/USB/USB4_P") (pintype "passive"))
    (pad "2" smd roundrect (at -0.749 0.001) (size 0.3 0.6) (layers "F.Cu" "F.Paste" "F.Mask") (roundrect_rratio 0.25)
      (net 1 "GND") (pintype "passive"))
    (pad "3" smd roundrect (at -0.749 0.497) (size 0.3 0.6) (layers "F.Cu" "F.Paste" "F.Mask") (roundrect_rratio 0.25)
      (net 77 "/USB/USB4_N") (pintype "passive"))
    (pad "4" smd roundrect (at 0.747 0.497) (size 0.3 0.6) (layers "F.Cu" "F.Paste" "F.Mask") (roundrect_rratio 0.25)
      (net 292 "/USB/USB4_TVS_N") (pintype "passive"))
    (pad "5" smd roundrect (at 0.747 0.001) (size 0.3 0.6) (layers "F.Cu" "F.Paste" "F.Mask") (roundrect_rratio 0.25)
      (net 87 "/USB/USB4_VBUS") (pintype "passive"))
    (pad "6" smd roundrect (at 0.747 -0.499) (size 0.3 0.6) (layers "F.Cu" "F.Paste" "F.Mask") (roundrect_rratio 0.25)
      (net 293 "/USB/USB4_TVS_P") (pintype "passive"))
  )
	(footprint "kria-k26-devboard-footprints:DFN-14-1EP_4x3mm_P0.5mm" (layer "F.Cu")
    (at 145.525 66.25)
    (property "Author" "Antmicro")
    (property "License" "Apache-2.0")
    (property "MPN" "LTC4358CDE#PBF")
    (property "Manufacturer" "Analog Devices")
    (property "Sheetfile" "supply-oring.kicad_sch")
    (property "Sheetname" "Supply ORing")
    (property "ki_description" "Ideal diode")
    (property "ki_keywords" "SMT, PMIC, IC, POWER, MANAGEMENT, DIODE, CONTROLLER")
    (attr smd)
    (fp_text reference "U57" (at -1.245 3.16) (layer "F.SilkS")
        (effects (font (size 0.7 0.7) (thickness 0.15)) (justify left bottom))
    )
    (fp_text value "LTC4358CDE" (at 0 3.2) (layer "F.Fab") hide
        (effects (font (size 0.7 0.7) (thickness 0.15)) (justify left bottom))
    )
    (fp_text user "Author: Antmicro" (at -0.659 6.998) (layer "F.Fab") hide
        (effects (font (size 0.7 0.7) (thickness 0.15)) (justify left bottom))
    )
    (fp_text user "License: Apache-2.0" (at -0.659 8.198) (layer "F.Fab") hide
        (effects (font (size 0.7 0.7) (thickness 0.15)) (justify left bottom))
    )
    (fp_text user "${REFERENCE}" (at -0.659 5.797) (layer "F.Fab") hide
        (effects (font (size 0.7 0.7) (thickness 0.15)) (justify left bottom))
    )
    (fp_line (start -1.6 -2.045) (end 1.5995 -2.045)
      (stroke (width 0.15) (type solid)) (layer "F.SilkS"))
    (fp_line (start -1.6 2.044) (end 1.6 2.044)
      (stroke (width 0.15) (type solid)) (layer "F.SilkS"))
    (fp_circle (center -1.85 -1.9) (end -1.8 -1.9)
      (stroke (width 0.15) (type solid)) (fill solid) (layer "F.SilkS"))
    (fp_line (start -2.1 -1.87) (end -1.79 -1.87)
      (stroke (width 0.05) (type solid)) (layer "F.CrtYd"))
    (fp_line (start -2.1 1.9) (end -2.1 -1.87)
      (stroke (width 0.05) (type solid)) (layer "F.CrtYd"))
    (fp_line (start -1.79 -2.28) (end 1.81 -2.28)
      (stroke (width 0.05) (type solid)) (layer "F.CrtYd"))
    (fp_line (start -1.79 -1.87) (end -1.79 -2.28)
      (stroke (width 0.05) (type solid)) (layer "F.CrtYd"))
    (fp_line (start -1.79 1.9) (end -2.1 1.9)
      (stroke (width 0.05) (type solid)) (layer "F.CrtYd"))
    (fp_line (start -1.79 2.31) (end -1.79 1.9)
      (stroke (width 0.05) (type solid)) (layer "F.CrtYd"))
    (fp_line (start 1.81 -2.28) (end 1.81 -1.87)
      (stroke (width 0.05) (type solid)) (layer "F.CrtYd"))
    (fp_line (start 1.81 1.9) (end 1.81 2.31)
      (stroke (width 0.05) (type solid)) (layer "F.CrtYd"))
    (fp_line (start 1.81 2.31) (end -1.79 2.31)
      (stroke (width 0.05) (type solid)) (layer "F.CrtYd"))
    (fp_line (start 2.1 -1.87) (end 1.81 -1.87)
      (stroke (width 0.05) (type solid)) (layer "F.CrtYd"))
    (fp_line (start 2.1 -1.87) (end 2.1 1.9)
      (stroke (width 0.05) (type solid)) (layer "F.CrtYd"))
    (fp_line (start 2.1 1.9) (end 1.81 1.9)
      (stroke (width 0.05) (type solid)) (layer "F.CrtYd"))
    (fp_line (start -1.55 -2.045) (end -1.55 2.044)
      (stroke (width 0.15) (type solid)) (layer "F.Fab"))
    (fp_line (start -1.55 2.044) (end 1.549 2.044)
      (stroke (width 0.15) (type solid)) (layer "F.Fab"))
    (fp_line (start 1.549 -2.045) (end -1.55 -2.045)
      (stroke (width 0.15) (type solid)) (layer "F.Fab"))
    (fp_line (start 1.549 2.044) (end 1.549 -2.045)
      (stroke (width 0.15) (type solid)) (layer "F.Fab"))
    (pad "" smd roundrect (at 0 -0.8) (size 1.3 1.3) (layers "F.Paste") (roundrect_rratio 0.05))
    (pad "" smd roundrect (at 0 0.8) (size 1.3 1.3) (layers "F.Paste") (roundrect_rratio 0.05))
    (pad "1" smd roundrect (at -1.445 -1.499) (size 0.807999 0.2548) (layers "F.Cu" "F.Paste" "F.Mask") (roundrect_rratio 0.25)
      (net 228 "/Power Supply/Supply ORing/PD_VBUS") (pinfunction "IN") (pintype "input"))
    (pad "2" smd roundrect (at -1.445 -1.001) (size 0.807999 0.2548) (layers "F.Cu" "F.Paste" "F.Mask") (roundrect_rratio 0.25)
      (net 228 "/Power Supply/Supply ORing/PD_VBUS") (pinfunction "IN") (pintype "passive"))
    (pad "3" smd roundrect (at -1.445 -0.5) (size 0.807999 0.2548) (layers "F.Cu" "F.Paste" "F.Mask") (roundrect_rratio 0.25)
      (net 228 "/Power Supply/Supply ORing/PD_VBUS") (pinfunction "IN") (pintype "passive"))
    (pad "4" smd roundrect (at -1.445 0) (size 0.807999 0.2548) (layers "F.Cu" "F.Paste" "F.Mask") (roundrect_rratio 0.25)
      (net 228 "/Power Supply/Supply ORing/PD_VBUS") (pinfunction "IN") (pintype "passive"))
    (pad "5" smd roundrect (at -1.445 0.5) (size 0.807999 0.2548) (layers "F.Cu" "F.Paste" "F.Mask") (roundrect_rratio 0.25)
      (net 788 "unconnected-(U57-GATE-Pad5)") (pinfunction "GATE") (pintype "output+no_connect"))
    (pad "6" smd roundrect (at -1.445 1) (size 0.807999 0.2548) (layers "F.Cu" "F.Paste" "F.Mask") (roundrect_rratio 0.25)
      (net 789 "unconnected-(U57-NC-Pad6)") (pinfunction "NC") (pintype "no_connect"))
    (pad "7" smd roundrect (at -1.445 1.5) (size 0.807999 0.2548) (layers "F.Cu" "F.Paste" "F.Mask") (roundrect_rratio 0.25)
      (net 1 "GND") (pinfunction "GND") (pintype "power_in"))
    (pad "8" smd roundrect (at 1.445 1.5) (size 0.807999 0.2548) (layers "F.Cu" "F.Paste" "F.Mask") (roundrect_rratio 0.25)
      (net 14 "/Power Supply/DC/DC conventers/DC_MAIN_BUS") (pinfunction "VDD") (pintype "passive"))
    (pad "9" smd roundrect (at 1.445 1) (size 0.807999 0.2548) (layers "F.Cu" "F.Paste" "F.Mask") (roundrect_rratio 0.25)
      (net 14 "/Power Supply/DC/DC conventers/DC_MAIN_BUS") (pinfunction "OUT") (pintype "passive"))
    (pad "10" smd roundrect (at 1.445 0.5) (size 0.807999 0.2548) (layers "F.Cu" "F.Paste" "F.Mask") (roundrect_rratio 0.25)
      (net 790 "unconnected-(U57-NC-Pad10)") (pinfunction "NC") (pintype "no_connect"))
    (pad "11" smd roundrect (at 1.445 0) (size 0.807999 0.2548) (layers "F.Cu" "F.Paste" "F.Mask") (roundrect_rratio 0.25)
      (net 228 "/Power Supply/Supply ORing/PD_VBUS") (pinfunction "IN") (pintype "passive"))
    (pad "12" smd roundrect (at 1.445 -0.501) (size 0.807999 0.2548) (layers "F.Cu" "F.Paste" "F.Mask") (roundrect_rratio 0.25)
      (net 228 "/Power Supply/Supply ORing/PD_VBUS") (pinfunction "IN") (pintype "passive"))
    (pad "13" smd roundrect (at 1.445 -1.001) (size 0.807999 0.2548) (layers "F.Cu" "F.Paste" "F.Mask") (roundrect_rratio 0.25)
      (net 228 "/Power Supply/Supply ORing/PD_VBUS") (pinfunction "IN") (pintype "passive"))
    (pad "14" smd roundrect (at 1.445 -1.499) (size 0.807999 0.2548) (layers "F.Cu" "F.Paste" "F.Mask") (roundrect_rratio 0.25)
      (net 228 "/Power Supply/Supply ORing/PD_VBUS") (pinfunction "IN") (pintype "passive"))
    (pad "15" smd roundrect (at 0 0) (size 1.8034 3.4036) (layers "F.Cu" "F.Mask") (roundrect_rratio 0.05)
      (net 14 "/Power Supply/DC/DC conventers/DC_MAIN_BUS") (pinfunction "DRAIN") (pintype "passive"))
  )
	(footprint "kria-k26-devboard-footprints:C_0402_1005Metric" (layer "F.Cu")
    (at 106.39 104.2 90)
    (descr "Capacitor SMD 0402")
    (tags "capacitor SMD 0402")
    (property "Author" "Antmicro")
    (property "Dielectric" "X5R")
    (property "License" "Apache-2.0")
    (property "MPN" "GRM155R61H104KE14D")
    (property "Manufacturer" "Murata")
    (property "Sheetfile" "clock.kicad_sch")
    (property "Sheetname" "Clock distribution")
    (property "Val" "100n")
    (property "Voltage" "50V")
    (property "ki_description" " ")
    (attr smd)
    (fp_text reference "C27" (at 0.81 0.45 90) (layer "F.SilkS")
        (effects (font (size 0.7 0.7) (thickness 0.15)) (justify left bottom))
    )
    (fp_text value "C_100n_0402" (at 0 1.4 90) (layer "F.Fab") hide
        (effects (font (size 0.7 0.7) (thickness 0.15)) (justify left bottom))
    )
    (fp_text user "License: Apache-2.0" (at -0.932 5.17 90) (layer "F.Fab") hide
        (effects (font (size 0.7 0.7) (thickness 0.15)) (justify left bottom))
    )
    (fp_text user "${REFERENCE}" (at -0.932 3.168 90) (layer "F.Fab") hide
        (effects (font (size 0.7 0.7) (thickness 0.15)) (justify left bottom))
    )
    (fp_text user "Author: Antmicro" (at -0.932 4.17 90) (layer "F.Fab") hide
        (effects (font (size 0.7 0.7) (thickness 0.15)) (justify left bottom))
    )
    (fp_rect (start -0.94 -0.47) (end 0.94 0.47)
      (stroke (width 0.05) (type solid)) (fill none) (layer "F.CrtYd"))
    (fp_rect (start -0.499 -0.249) (end 0.499 0.249)
      (stroke (width 0.15) (type solid)) (fill none) (layer "F.Fab"))
    (pad "1" smd roundrect (at -0.484 0 90) (size 0.59 0.64) (layers "F.Cu" "F.Paste" "F.Mask") (roundrect_rratio 0.25)
      (net 15 "PS_3V3") (pintype "passive"))
    (pad "2" smd roundrect (at 0.484 0 90) (size 0.59 0.64) (layers "F.Cu" "F.Paste" "F.Mask") (roundrect_rratio 0.25)
      (net 1 "GND") (pintype "passive"))
  )
)
